(kicad_pcb
	(version 20260206)
	(generator "pcbnew")
	(generator_version "10.0")
	(general
		(thickness 1.6)
		(legacy_teardrops no)
	)
	(paper "A4")
	(title_block
		(title "Wiwynn_Tioga_Pass_MB.brd")
		(comment 1 "Tioga Pass / footprints 845-852 of 4770")
	)
	(layers
		(0 "F.Cu" signal "TOP")
		(4 "In1.Cu" signal "L2GND")
		(6 "In2.Cu" signal "L3")
		(8 "In3.Cu" signal "L4GND")
		(10 "In4.Cu" signal "L5")
		(12 "In5.Cu" signal "L6GND")
		(14 "In6.Cu" signal "L7VCC")
		(16 "In7.Cu" signal "L8VCC")
		(18 "In8.Cu" signal "L9GND")
		(20 "In9.Cu" signal "L10")
		(22 "In10.Cu" signal "L11GND")
		(24 "In11.Cu" signal "L12")
		(26 "In12.Cu" signal "L13GND")
		(2 "B.Cu" signal "BOTTOM")
		(9 "F.Adhes" user "F.Adhesive")
		(11 "B.Adhes" user "B.Adhesive")
		(13 "F.Paste" user "Package Geometry/Pastemask Top")
		(15 "B.Paste" user "Package Geometry/Pastemask Bottom")
		(5 "F.SilkS" user "Ref Des/Silkscreen Top")
		(7 "B.SilkS" user "Ref Des/Silkscreen Bottom")
		(1 "F.Mask" user "Board Geometry/Soldermask Top")
		(3 "B.Mask" user "Board Geometry/Soldermask Bottom")
		(17 "Dwgs.User" user "User.Drawings")
		(19 "Cmts.User" user "User.Comments")
		(21 "Eco1.User" user "User.Eco1")
		(23 "Eco2.User" user "User.Eco2")
		(25 "Edge.Cuts" user "Board Geometry/Outline")
		(27 "Margin" user)
		(31 "F.CrtYd" user "Package Geometry/Place Bound Top")
		(29 "B.CrtYd" user "Package Geometry/Place Bound Bottom")
		(35 "F.Fab" user "Ref Des/Assembly Top")
		(33 "B.Fab" user "Ref Des/Assembly Bottom")
	)
	(footprint ""
		(layer "F.Cu")
		(at 197.19798 -77.216 -90)
		(property "Reference" "C4D7"
			(at -0.8382 -0.67818 270)
			(unlocked yes)
			(layer "F.SilkS")
			(effects
				(font
					(size 0.4064 0.254)
					(thickness 0.1524)
				)
				(justify left)
			)
		)
		(property "Value" ""
			(at 0 0 270)
			(layer "F.Fab")
			(effects
				(font
					(size 1.27 1.27)
				)
			)
		)
		(duplicate_pad_numbers_are_jumpers no)
		(fp_poly
			(pts
				(xy 0.3048 -0.1016) (xy 0.3048 0.9906) (xy -0.3048 0.9906) (xy -0.3048 -0.1016)
			)
			(stroke
				(width 0)
				(type default)
			)
			(fill no)
			(layer "F.CrtYd")
		)
		(fp_line
			(start -0.3048 0.9906)
			(end 0.3048 0.9906)
			(stroke
				(width 0.1)
				(type default)
			)
			(layer "F.Fab")
		)
		(fp_line
			(start 0.3048 0.9906)
			(end 0.3048 -0.1016)
			(stroke
				(width 0.1)
				(type default)
			)
			(layer "F.Fab")
		)
		(fp_line
			(start -0.3048 -0.1016)
			(end -0.3048 0.9906)
			(stroke
				(width 0.1)
				(type default)
			)
			(layer "F.Fab")
		)
		(fp_line
			(start 0.3048 -0.1016)
			(end -0.3048 -0.1016)
			(stroke
				(width 0.1)
				(type default)
			)
			(layer "F.Fab")
		)
		(pad "1" smd rect
			(at 0 0 270)
			(size 0.508 0.508)
			(layers "F.Cu" "F.Mask" "F.Paste")
			(net "VR_PVCCIN_CPU0_PH4_VCIN")
		)
		(pad "2" smd rect
			(at 0 0.889 270)
			(size 0.508 0.508)
			(layers "F.Cu" "F.Mask" "F.Paste")
			(net "GND")
		)
		(zone
			(layer "F.Cu")
			(hatch none 0.5)
			(connect_pads
				(clearance 0)
			)
			(min_thickness 0.25)
			(keepout
				(tracks not_allowed)
				(vias allowed)
				(pads allowed)
				(copperpour not_allowed)
				(footprints allowed)
			)
			(placement
				(enabled no)
				(sheetname "")
			)
			(fill
				(thermal_gap 0.5)
				(thermal_bridge_width 0.5)
				(island_removal_mode 0)
			)
			(polygon
				(pts
					(xy 196.56298 -77.47) (xy 196.56298 -76.962) (xy 196.94398 -76.962) (xy 196.94398 -77.47)
				)
			)
		)
		(zone
			(layer "F.Cu")
			(hatch none 0.5)
			(connect_pads
				(clearance 0)
			)
			(min_thickness 0.25)
			(keepout
				(tracks allowed)
				(vias not_allowed)
				(pads allowed)
				(copperpour not_allowed)
				(footprints allowed)
			)
			(placement
				(enabled no)
				(sheetname "")
			)
			(fill
				(thermal_gap 0.5)
				(thermal_bridge_width 0.5)
				(island_removal_mode 0)
			)
			(polygon
				(pts
					(xy 196.94398 -77.47) (xy 196.94398 -76.962) (xy 196.56298 -76.962) (xy 196.56298 -77.47)
				)
			)
		)
	)
	(footprint ""
		(layer "F.Cu")
		(at 409.719526 -76.883768)
		(property "Reference" "RM8D1"
			(at -4.496562 1.28778 90)
			(unlocked yes)
			(layer "F.SilkS")
			(effects
				(font
					(size 0.7874 0.5842)
					(thickness 0.1524)
				)
				(justify left)
			)
		)
		(property "Value" ""
			(at 0 0 0)
			(layer "F.Fab")
			(effects
				(font
					(size 1.27 1.27)
				)
			)
		)
		(duplicate_pad_numbers_are_jumpers no)
		(fp_poly
			(pts
				(arc
					(start 3.5052 0)
					(mid -3.5052 0)
					(end 3.5052 0)
				)
			)
			(stroke
				(width 0)
				(type default)
			)
			(fill yes)
			(layer "F.Paste")
		)
		(fp_poly
			(pts
				(arc
					(start 3.050032 0)
					(mid -3.050032 0)
					(end 3.050032 0)
				)
			)
			(stroke
				(width 0)
				(type default)
			)
			(fill no)
			(layer "F.CrtYd")
		)
		(fp_circle
			(center 0 0)
			(end 3.050032 0)
			(stroke
				(width 0.1)
				(type default)
			)
			(fill no)
			(layer "F.Fab")
		)
		(pad "1" thru_hole circle
			(at 0 0)
			(size 7.0104 7.0104)
			(drill 4.4958)
			(layers "*.Cu" "*.Mask")
			(remove_unused_layers no)
			(net "GND")
			(clearance -0.9398)
		)
	)
	(footprint ""
		(layer "F.Cu")
		(at 389.636 -0.254)
		(property "Reference" "R7G18"
			(at 0 0 0)
			(layer "F.SilkS")
			(hide yes)
			(effects
				(font
					(size 1.27 1.27)
				)
			)
		)
		(property "Value" ""
			(at 0 0 0)
			(layer "F.Fab")
			(effects
				(font
					(size 1.27 1.27)
				)
			)
		)
		(duplicate_pad_numbers_are_jumpers no)
		(fp_poly
			(pts
				(xy -0.2794 -0.1016) (xy 0.2794 -0.1016) (xy 0.2794 0.9906) (xy -0.2794 0.9906)
			)
			(stroke
				(width 0)
				(type default)
			)
			(fill no)
			(layer "F.CrtYd")
		)
		(fp_line
			(start -0.2794 -0.1016)
			(end -0.2794 0.9906)
			(stroke
				(width 0.1)
				(type default)
			)
			(layer "F.Fab")
		)
		(fp_line
			(start -0.2794 0.9906)
			(end 0.2794 0.9906)
			(stroke
				(width 0.1)
				(type default)
			)
			(layer "F.Fab")
		)
		(fp_line
			(start 0.2794 -0.1016)
			(end -0.2794 -0.1016)
			(stroke
				(width 0.1)
				(type default)
			)
			(layer "F.Fab")
		)
		(fp_line
			(start 0.2794 0.9906)
			(end 0.2794 -0.1016)
			(stroke
				(width 0.1)
				(type default)
			)
			(layer "F.Fab")
		)
		(pad "1" smd rect
			(at 0 0)
			(size 0.508 0.508)
			(layers "F.Cu" "F.Mask" "F.Paste")
			(net "JTAG_PCH_PLD_TDI")
		)
		(pad "2" smd rect
			(at 0 0.889)
			(size 0.508 0.508)
			(layers "F.Cu" "F.Mask" "F.Paste")
			(net "JTAG_TDI")
		)
		(zone
			(layer "F.Cu")
			(hatch none 0.5)
			(connect_pads
				(clearance 0)
			)
			(min_thickness 0.25)
			(keepout
				(tracks allowed)
				(vias not_allowed)
				(pads allowed)
				(copperpour not_allowed)
				(footprints allowed)
			)
			(placement
				(enabled no)
				(sheetname "")
			)
			(fill
				(thermal_gap 0.5)
				(thermal_bridge_width 0.5)
				(island_removal_mode 0)
			)
			(polygon
				(pts
					(xy 389.382 0) (xy 389.89 0) (xy 389.89 0.381) (xy 389.382 0.381)
				)
			)
		)
		(zone
			(layer "F.Cu")
			(hatch none 0.5)
			(connect_pads
				(clearance 0)
			)
			(min_thickness 0.25)
			(keepout
				(tracks not_allowed)
				(vias allowed)
				(pads allowed)
				(copperpour not_allowed)
				(footprints allowed)
			)
			(placement
				(enabled no)
				(sheetname "")
			)
			(fill
				(thermal_gap 0.5)
				(thermal_bridge_width 0.5)
				(island_removal_mode 0)
			)
			(polygon
				(pts
					(xy 389.382 0.381) (xy 389.89 0.381) (xy 389.89 0) (xy 389.382 0)
				)
			)
		)
	)
	(footprint ""
		(layer "F.Cu")
		(at 4.445 -134.3914 -90)
		(property "Reference" "RT6"
			(at 0 0 270)
			(layer "F.SilkS")
			(hide yes)
			(effects
				(font
					(size 1.27 1.27)
				)
			)
		)
		(property "Value" "*"
			(at -0.0254 -2.6289 270)
			(unlocked yes)
			(layer "F.Fab")
			(hide yes)
			(effects
				(font
					(size 1.27 1.016)
					(thickness 0.1524)
				)
			)
		)
		(property "Device Type" "1R3F-GP_RCL_GP-1R3F-GP,64.1R00A"
			(at -0.0254 -4.1529 270)
			(unlocked yes)
			(layer "F.Fab")
			(hide yes)
			(effects
				(font
					(size 1.27 1.016)
					(thickness 0.1524)
				)
			)
		)
		(duplicate_pad_numbers_are_jumpers no)
		(fp_line
			(start -0.4826 0)
			(end -0.2032 0)
			(stroke
				(width 0.2032)
				(type default)
			)
			(layer "F.SilkS")
		)
		(fp_line
			(start 0.2032 0)
			(end 0.4826 0)
			(stroke
				(width 0.2032)
				(type default)
			)
			(layer "F.SilkS")
		)
		(fp_rect
			(start -0.5842 1.3335)
			(end 0.5842 -1.3335)
			(stroke
				(width 0)
				(type default)
			)
			(fill no)
			(layer "F.CrtYd")
		)
		(fp_rect
			(start -0.5842 1.3335)
			(end 0.5842 -1.3335)
			(stroke
				(width 0)
				(type default)
			)
			(fill no)
			(layer "F.Fab")
		)
		(pad "1" smd custom
			(at 0 -0.762 270)
			(size 0.2159 0.2159)
			(layers "F.Cu" "F.Mask" "F.Paste")
			(net "VR_PVDDQ_KLM_PH1_RC")
			(options
				(clearance outline)
				(anchor circle)
			)
			(primitives
				(gr_poly
					(pts
						(arc
							(start -0.3302 -0.4318)
							(mid -0.402042 -0.402042)
							(end -0.4318 -0.3302)
						)
						(arc
							(start -0.4318 0.3302)
							(mid -0.402042 0.402042)
							(end -0.3302 0.4318)
						)
						(arc
							(start 0.3302 0.4318)
							(mid 0.402042 0.402042)
							(end 0.4318 0.3302)
						)
						(arc
							(start 0.4318 -0.3302)
							(mid 0.402042 -0.402042)
							(end 0.3302 -0.4318)
						)
					)
					(width 0)
					(fill yes)
				)
			)
		)
		(pad "2" smd custom
			(at 0 0.762 270)
			(size 0.2159 0.2159)
			(layers "F.Cu" "F.Mask" "F.Paste")
			(net "GND")
			(options
				(clearance outline)
				(anchor circle)
			)
			(primitives
				(gr_poly
					(pts
						(arc
							(start -0.3302 -0.4318)
							(mid -0.402042 -0.402042)
							(end -0.4318 -0.3302)
						)
						(arc
							(start -0.4318 0.3302)
							(mid -0.402042 0.402042)
							(end -0.3302 0.4318)
						)
						(arc
							(start 0.3302 0.4318)
							(mid 0.402042 0.402042)
							(end 0.4318 0.3302)
						)
						(arc
							(start 0.4318 -0.3302)
							(mid 0.402042 -0.402042)
							(end 0.3302 -0.4318)
						)
					)
					(width 0)
					(fill yes)
				)
			)
		)
	)
	(footprint ""
		(layer "F.Cu")
		(at 167.4876 -149.225 -90)
		(property "Reference" "C4A6"
			(at 0 0 270)
			(layer "F.SilkS")
			(hide yes)
			(effects
				(font
					(size 1.27 1.27)
				)
			)
		)
		(property "Value" ""
			(at 0 0 270)
			(layer "F.Fab")
			(effects
				(font
					(size 1.27 1.27)
				)
			)
		)
		(duplicate_pad_numbers_are_jumpers no)
		(fp_rect
			(start -0.3048 -0.1016)
			(end 0.3048 0.9906)
			(stroke
				(width 0)
				(type default)
			)
			(fill no)
			(layer "F.CrtYd")
		)
		(fp_line
			(start -0.3048 0.9906)
			(end 0.3048 0.9906)
			(stroke
				(width 0.1)
				(type default)
			)
			(layer "F.Fab")
		)
		(fp_line
			(start 0.3048 0.9906)
			(end 0.3048 -0.1016)
			(stroke
				(width 0.1)
				(type default)
			)
			(layer "F.Fab")
		)
		(fp_line
			(start -0.3048 -0.1016)
			(end -0.3048 0.9906)
			(stroke
				(width 0.1)
				(type default)
			)
			(layer "F.Fab")
		)
		(fp_line
			(start 0.3048 -0.1016)
			(end -0.3048 -0.1016)
			(stroke
				(width 0.1)
				(type default)
			)
			(layer "F.Fab")
		)
		(pad "1" smd rect
			(at 0 0 270)
			(size 0.508 0.508)
			(layers "F.Cu" "F.Mask" "F.Paste")
			(net "FM_PVTT_KLM_EN_R")
		)
		(pad "2" smd rect
			(at 0 0.889 270)
			(size 0.508 0.508)
			(layers "F.Cu" "F.Mask" "F.Paste")
			(net "GND")
		)
		(zone
			(layer "F.Cu")
			(hatch none 0.5)
			(connect_pads
				(clearance 0)
			)
			(min_thickness 0.25)
			(keepout
				(tracks allowed)
				(vias not_allowed)
				(pads allowed)
				(copperpour not_allowed)
				(footprints allowed)
			)
			(placement
				(enabled no)
				(sheetname "")
			)
			(fill
				(thermal_gap 0.5)
				(thermal_bridge_width 0.5)
				(island_removal_mode 0)
			)
			(polygon
				(pts
					(xy 167.2336 -149.479) (xy 166.8526 -149.479) (xy 166.8526 -148.971) (xy 167.2336 -148.971)
				)
			)
		)
		(zone
			(layer "F.Cu")
			(hatch none 0.5)
			(connect_pads
				(clearance 0)
			)
			(min_thickness 0.25)
			(keepout
				(tracks not_allowed)
				(vias allowed)
				(pads allowed)
				(copperpour not_allowed)
				(footprints allowed)
			)
			(placement
				(enabled no)
				(sheetname "")
			)
			(fill
				(thermal_gap 0.5)
				(thermal_bridge_width 0.5)
				(island_removal_mode 0)
			)
			(polygon
				(pts
					(xy 167.2336 -149.479) (xy 166.8526 -149.479) (xy 166.8526 -148.971) (xy 167.2336 -148.971)
				)
			)
		)
	)
	(footprint ""
		(layer "F.Cu")
		(at 192.786 -66.06667 90)
		(property "Reference" "RT3"
			(at 1.01473 0.656336 0)
			(unlocked yes)
			(layer "F.SilkS")
			(effects
				(font
					(size 0.4064 0.254)
					(thickness 0.1524)
				)
			)
		)
		(property "Value" ""
			(at 0 0 90)
			(layer "F.Fab")
			(effects
				(font
					(size 1.27 1.27)
				)
			)
		)
		(duplicate_pad_numbers_are_jumpers no)
		(fp_poly
			(pts
				(xy -0.4953 -0.2032) (xy 0.4953 -0.2032) (xy 0.4953 1.6002) (xy -0.4953 1.6002)
			)
			(stroke
				(width 0)
				(type default)
			)
			(fill no)
			(layer "F.CrtYd")
		)
		(fp_line
			(start 0.4953 -0.2032)
			(end 0.4953 1.6002)
			(stroke
				(width 0.1)
				(type default)
			)
			(layer "F.Fab")
		)
		(fp_line
			(start -0.4953 -0.2032)
			(end 0.4953 -0.2032)
			(stroke
				(width 0.1)
				(type default)
			)
			(layer "F.Fab")
		)
		(fp_line
			(start 0.4953 1.6002)
			(end -0.4953 1.6002)
			(stroke
				(width 0.1)
				(type default)
			)
			(layer "F.Fab")
		)
		(fp_line
			(start -0.4953 1.6002)
			(end -0.4953 -0.2032)
			(stroke
				(width 0.1)
				(type default)
			)
			(layer "F.Fab")
		)
		(pad "1" smd rect
			(at 0 0 90)
			(size 0.762 0.889)
			(layers "F.Cu" "F.Mask" "F.Paste")
			(net "VR_PVCCIN_CPU0_PH2_BOOT")
		)
		(pad "2" smd rect
			(at 0 1.397 90)
			(size 0.762 0.889)
			(layers "F.Cu" "F.Mask" "F.Paste")
			(net "VR_PVCCIN_CPU0_PH2_BOOT_R")
		)
		(zone
			(layer "F.Cu")
			(hatch none 0.5)
			(connect_pads
				(clearance 0)
			)
			(min_thickness 0.25)
			(keepout
				(tracks allowed)
				(vias not_allowed)
				(pads allowed)
				(copperpour not_allowed)
				(footprints allowed)
			)
			(placement
				(enabled no)
				(sheetname "")
			)
			(fill
				(thermal_gap 0.5)
				(thermal_bridge_width 0.5)
				(island_removal_mode 0)
			)
			(polygon
				(pts
					(xy 193.7385 -66.44767) (xy 193.2305 -66.44767) (xy 193.2305 -65.68567) (xy 193.7385 -65.68567)
				)
			)
		)
		(zone
			(layer "F.Cu")
			(hatch none 0.5)
			(connect_pads
				(clearance 0)
			)
			(min_thickness 0.25)
			(keepout
				(tracks not_allowed)
				(vias allowed)
				(pads allowed)
				(copperpour not_allowed)
				(footprints allowed)
			)
			(placement
				(enabled no)
				(sheetname "")
			)
			(fill
				(thermal_gap 0.5)
				(thermal_bridge_width 0.5)
				(island_removal_mode 0)
			)
			(polygon
				(pts
					(xy 193.7385 -65.68567) (xy 193.7385 -66.44767) (xy 193.2305 -66.44767) (xy 193.2305 -65.68567)
				)
			)
		)
	)
	(footprint ""
		(layer "F.Cu")
		(at 397.750538 -75.050396)
		(property "Reference" "U8E2"
			(at 2.79908 2.95783 180)
			(unlocked yes)
			(layer "F.SilkS")
			(effects
				(font
					(size 0.7874 0.5842)
					(thickness 0.1524)
				)
				(justify left)
			)
		)
		(property "Value" ""
			(at 0 0 0)
			(layer "F.Fab")
			(effects
				(font
					(size 1.27 1.27)
				)
			)
		)
		(duplicate_pad_numbers_are_jumpers no)
		(fp_line
			(start 0.381 0.635)
			(end 0.381 1.27)
			(stroke
				(width 0.1524)
				(type default)
			)
			(layer "F.SilkS")
		)
		(fp_line
			(start 0.9525 -0.5715)
			(end 1.778 -0.5715)
			(stroke
				(width 0.1524)
				(type default)
			)
			(layer "F.SilkS")
		)
		(fp_line
			(start 0.9525 2.4765)
			(end 1.778 2.4765)
			(stroke
				(width 0.1524)
				(type default)
			)
			(layer "F.SilkS")
		)
		(fp_line
			(start 1.778 -0.5715)
			(end 1.778 0.3175)
			(stroke
				(width 0.1524)
				(type default)
			)
			(layer "F.SilkS")
		)
		(fp_line
			(start 1.778 2.4765)
			(end 1.778 1.5875)
			(stroke
				(width 0.1524)
				(type default)
			)
			(layer "F.SilkS")
		)
		(fp_circle
			(center -0.9525 -0.9271)
			(end -0.8255 -0.9271)
			(stroke
				(width 0.254)
				(type default)
			)
			(fill no)
			(layer "F.SilkS")
		)
		(fp_poly
			(pts
				(xy 1.778 2.4765) (xy 0.381 2.4765) (xy 0.381 -0.5715) (xy 1.778 -0.5715)
			)
			(stroke
				(width 0)
				(type default)
			)
			(fill no)
			(layer "F.CrtYd")
		)
		(fp_line
			(start 0.381 -0.5715)
			(end 0.381 2.4765)
			(stroke
				(width 0.1)
				(type default)
			)
			(layer "F.Fab")
		)
		(fp_line
			(start 0.381 2.4765)
			(end 1.778 2.4765)
			(stroke
				(width 0.1)
				(type default)
			)
			(layer "F.Fab")
		)
		(fp_line
			(start 1.778 -0.5715)
			(end 0.381 -0.5715)
			(stroke
				(width 0.1)
				(type default)
			)
			(layer "F.Fab")
		)
		(fp_line
			(start 1.778 2.4765)
			(end 1.778 -0.5715)
			(stroke
				(width 0.1)
				(type default)
			)
			(layer "F.Fab")
		)
		(fp_circle
			(center -0.9525 -0.9271)
			(end -0.8255 -0.9271)
			(stroke
				(width 0.254)
				(type default)
			)
			(fill no)
			(layer "F.Fab")
		)
		(pad "1" smd rect
			(at 0 0)
			(size 1.143 0.508)
			(layers "F.Cu" "F.Mask" "F.Paste")
			(net "GND")
		)
		(pad "2" smd rect
			(at 0 1.905)
			(size 1.143 0.508)
			(layers "F.Cu" "F.Mask" "F.Paste")
			(net "PWRGD_P12V_HSC_DLY_R")
		)
		(pad "3" smd rect
			(at 2.159 0.9525)
			(size 1.143 0.508)
			(layers "F.Cu" "F.Mask" "F.Paste")
			(net "PWRGD_P12V_HSC")
		)
	)
	(footprint ""
		(layer "F.Cu")
		(at 410.806138 -106.384598 90)
		(property "Reference" "R8C20"
			(at 0 0 90)
			(layer "F.SilkS")
			(hide yes)
			(effects
				(font
					(size 1.27 1.27)
				)
			)
		)
		(property "Value" ""
			(at 0 0 90)
			(layer "F.Fab")
			(effects
				(font
					(size 1.27 1.27)
				)
			)
		)
		(duplicate_pad_numbers_are_jumpers no)
		(fp_poly
			(pts
				(xy -0.2794 -0.1016) (xy 0.2794 -0.1016) (xy 0.2794 0.9906) (xy -0.2794 0.9906)
			)
			(stroke
				(width 0)
				(type default)
			)
			(fill no)
			(layer "F.CrtYd")
		)
		(fp_line
			(start 0.2794 -0.1016)
			(end -0.2794 -0.1016)
			(stroke
				(width 0.1)
				(type default)
			)
			(layer "F.Fab")
		)
		(fp_line
			(start -0.2794 -0.1016)
			(end -0.2794 0.9906)
			(stroke
				(width 0.1)
				(type default)
			)
			(layer "F.Fab")
		)
		(fp_line
			(start 0.2794 0.9906)
			(end 0.2794 -0.1016)
			(stroke
				(width 0.1)
				(type default)
			)
			(layer "F.Fab")
		)
		(fp_line
			(start -0.2794 0.9906)
			(end 0.2794 0.9906)
			(stroke
				(width 0.1)
				(type default)
			)
			(layer "F.Fab")
		)
		(pad "1" smd rect
			(at 0 0 90)
			(size 0.508 0.508)
			(layers "F.Cu" "F.Mask" "F.Paste")
			(net "SMB_HOST_STBY_LVC3_SDA_R1")
		)
		(pad "2" smd rect
			(at 0 0.889 90)
			(size 0.508 0.508)
			(layers "F.Cu" "F.Mask" "F.Paste")
			(net "SMB_HOST_STBY_LVC3_SDA")
		)
		(zone
			(layer "F.Cu")
			(hatch none 0.5)
			(connect_pads
				(clearance 0)
			)
			(min_thickness 0.25)
			(keepout
				(tracks allowed)
				(vias not_allowed)
				(pads allowed)
				(copperpour not_allowed)
				(footprints allowed)
			)
			(placement
				(enabled no)
				(sheetname "")
			)
			(fill
				(thermal_gap 0.5)
				(thermal_bridge_width 0.5)
				(island_removal_mode 0)
			)
			(polygon
				(pts
					(xy 411.060138 -106.130598) (xy 411.060138 -106.638598) (xy 411.441138 -106.638598) (xy 411.441138 -106.130598)
				)
			)
		)
		(zone
			(layer "F.Cu")
			(hatch none 0.5)
			(connect_pads
				(clearance 0)
			)
			(min_thickness 0.25)
			(keepout
				(tracks not_allowed)
				(vias allowed)
				(pads allowed)
				(copperpour not_allowed)
				(footprints allowed)
			)
			(placement
				(enabled no)
				(sheetname "")
			)
			(fill
				(thermal_gap 0.5)
				(thermal_bridge_width 0.5)
				(island_removal_mode 0)
			)
			(polygon
				(pts
					(xy 411.441138 -106.130598) (xy 411.441138 -106.638598) (xy 411.060138 -106.638598) (xy 411.060138 -106.130598)
				)
			)
		)
	)
)
